# S9S_MB_2U (Grand Teton) — schematic parts with pin connectivity, parts 5880–5880 of 6093; source: Cadence DE-HDL packaged netlist (pstxprt.dat, pstxnet.dat, pstchip.dat)

U2  SOCKET4677_AZIF0045P001C01CS  SOCKET4677_AZIF0045-P001C01CS IO  pkg SOCKET4677_82X64-5XA_H466  page 13  (pins 2609-2934 of 4677)
  DE78  UPI3_RX_DP16  IN  = GND
  DE80  UPI3_RX_DN13  IN  = GND
  DE82  VSS1011  POWER  = GND
  DE84  VSS1012  POWER  = GND
  DE86  PE3_TX_DP10  OUT  = P5E_CPU0_PE3_TX_DP<10>
  DE88  VSS1015  POWER  = GND
  DE90  PE3_RX_DP11  IN  = P5E_CPU0_PE3_RX_DP<11>
  DF2  UPI1_RX_DP11  IN  = UPI_CPU1_CPU0_P0P1_DP<11>
  DF4  VSS1017  POWER  = GND
  DF6  UPI1_TX_DP10  OUT  = UPI_CPU0_CPU1_P1P0_DN<10>
  DF8  VSS1019  POWER  = GND
  DF10  PE2_RX_DP4  IN  = P5E_CPU0_PE2_RX_DP<4>
  DF12  VSS798  POWER  = GND
  DF14  PE2_TX_DN5  OUT  = P5E_CPU0_PE2_TX_DN<5>
  DF16  VSS799  POWER  = GND
  DF18  DDR7_SB_DQS_DN8  BI  = M_H_CPU0_SB_DQS_DN<8>
  DF20  DDR7_SB_DQ26  BI  = M_H_CPU0_SB_DQ<26>
  DF22  DDR7_SB_DQ15  BI  = M_H_CPU0_SB_DQ<15>
  DF24  DDR7_SB_DQS_DP6  BI  = M_H_CPU0_SB_DQS_DP<6>
  DF26  DDR7_SB_DQ10  BI  = M_H_CPU0_SB_DQ<10>
  DF28  DDR7_SB_DQ5  BI  = M_H_CPU0_SB_DQ<5>
  DF30  DDR7_SB_DQS_DP5  BI  = M_H_CPU0_SB_DQS_DP<5>
  DF32  DDR7_SB_DQ2  BI  = M_H_CPU0_SB_DQ<2>
  DF34  DDR7_SB_ECC3  BI  = M_H_CPU0_SB_CB<3>
  DF36  DDR7_SB_DQS_DP4  BI  = M_H_CPU0_SB_DQS_DP<4>
  DF38  DDR7_SB_ECC4  BI  = M_H_CPU0_SB_CB<4>
  DF40  DDR7_SB_CA0  OUT  = M_H_CPU0_SB_CA<0>
  DF42  DDR7_CLK_DP0  OUT  = M_H_CPU0_CLK_DP<0>
  DF44  DDR4_B_RSP0  IN  = M_E_CPU0_SB_RSP<0>
  DF47  DDR7_SA_CA5  OUT  = M_H_CPU0_SA_CA<5>
  DF49  VSS802  POWER  = GND
  DF51  DDR7_SA_CS_N0  OUT  = M_H_CPU0_SA_CS_N<0>
  DF53  DDR7_SA_ECC7  BI  = M_H_CPU0_SA_CB<7>
  DF55  DDR7_SA_DQS_DP9  BI  = M_H_CPU0_SA_DQS_DP<9>
  DF57  DDR7_SA_ECC2  BI  = M_H_CPU0_SA_CB<2>
  DF59  DDR7_SA_DQ31  BI  = M_H_CPU0_SA_DQ<31>
  DF61  DDR7_SA_DQS_DP8  BI  = M_H_CPU0_SA_DQS_DP<8>
  DF63  DDR7_SA_DQ26  BI  = M_H_CPU0_SA_DQ<26>
  DF65  DDR7_SA_DQ23  BI  = M_H_CPU0_SA_DQ<23>
  DF67  DDR7_SA_DQS_DP7  BI  = M_H_CPU0_SA_DQS_DP<7>
  DF69  DDR7_SA_DQ18  BI  = M_H_CPU0_SA_DQ<18>
  DF71  DDR7_SA_DQ15  BI  = M_H_CPU0_SA_DQ<15>
  DF73  DDR7_SA_DQS_DP6  BI  = M_H_CPU0_SA_DQS_DP<6>
  DF75  DDR7_SA_DQ10  BI  = M_H_CPU0_SA_DQ<10>
  DF77  UPI3_RX_DN16  IN  = GND
  DF79  VSS1018  POWER  = GND
  DF81  UPI3_RX_DP13  IN  = GND
  DF83  UPI3_RX_DN12  IN  = GND
  DF85  PE3_TX_DN9  OUT  = P5E_CPU0_PE3_TX_DN<9>
  DF87  VSS1020  POWER  = GND
  DF89  PE3_RX_DP10  IN  = P5E_CPU0_PE3_RX_DP<10>
  DF91  VSS806  POWER  = GND
  DG1  VSS807  POWER  = GND
  DG3  UPI1_RX_DN10  IN  = UPI_CPU1_CPU0_P0P1_DN<10>
  DG5  VSS1031  POWER  = GND
  DG7  UPI1_TX_DP9  OUT  = UPI_CPU0_CPU1_P1P0_DP<9>
  DG9  VSS1038  POWER  = GND
  DG11  PE2_RX_DP5  IN  = P5E_CPU0_PE2_RX_DP<5>
  DG13  VSS808  POWER  = GND
  DG15  PE2_TX_DP5  OUT  = P5E_CPU0_PE2_TX_DP<5>
  DG17  DDR7_SB_DQ28  BI  = M_H_CPU0_SB_DQ<28>
  DG19  DDR7_SB_DQ27  BI  = M_H_CPU0_SB_DQ<27>
  DG21  VSS809  POWER  = GND
  DG23  DDR7_SB_DQ14  BI  = M_H_CPU0_SB_DQ<14>
  DG25  DDR7_SB_DQ11  BI  = M_H_CPU0_SB_DQ<11>
  DG27  VSS1022  POWER  = GND
  DG29  DDR7_SB_DQ6  BI  = M_H_CPU0_SB_DQ<6>
  DG31  DDR7_SB_DQ3  BI  = M_H_CPU0_SB_DQ<3>
  DG33  VSS1024  POWER  = GND
  DG35  DDR7_SB_ECC2  BI  = M_H_CPU0_SB_CB<2>
  DG37  DDR7_SB_ECC5  BI  = M_H_CPU0_SB_CB<5>
  DG39  VSS1027  POWER  = GND
  DG41  DDR7_SB_CA1  OUT  = M_H_CPU0_SB_CA<1>
  DG43  DDR4_B_RSP1  IN  = M_E_CPU0_SB_RSP<1>
  DG45  VSS1030  POWER  = GND
  DG48  DDR7_SA_CA3  OUT  = M_H_CPU0_SA_CA<3>
  DG50  DDR7_SA_CS_N1  OUT  = M_H_CPU0_SA_CS_N<1>
  DG52  VSS817  POWER  = GND
  DG54  DDR7_SA_ECC6  BI  = M_H_CPU0_SA_CB<6>
  DG56  DDR7_SA_ECC3  BI  = M_H_CPU0_SA_CB<3>
  DG58  VSS820  POWER  = GND
  DG60  DDR7_SA_DQ30  BI  = M_H_CPU0_SA_DQ<30>
  DG62  DDR7_SA_DQ27  BI  = M_H_CPU0_SA_DQ<27>
  DG64  VSS821  POWER  = GND
  DG66  DDR7_SA_DQ22  BI  = M_H_CPU0_SA_DQ<22>
  DG68  DDR7_SA_DQ19  BI  = M_H_CPU0_SA_DQ<19>
  DG70  VSS1032  POWER  = GND
  DG72  DDR7_SA_DQ14  BI  = M_H_CPU0_SA_DQ<14>
  DG74  DDR7_SA_DQ11  BI  = M_H_CPU0_SA_DQ<11>
  DG76  VSS1033  POWER  = GND
  DG78  UPI3_RX_DN10  IN  = GND
  DG80  VSS1034  POWER  = GND
  DG82  UPI3_RX_DP11  IN  = GND
  DG84  VSS1035  POWER  = GND
  DG86  PE3_TX_DP9  OUT  = P5E_CPU0_PE3_TX_DP<9>
  DG88  VSS1037  POWER  = GND
  DG90  PE3_RX_DN10  IN  = P5E_CPU0_PE3_RX_DN<10>
  DH2  UPI1_RX_DP10  IN  = UPI_CPU1_CPU0_P0P1_DP<10>
  DH4  VSS1044  POWER  = GND
  DH6  UPI1_TX_DN9  OUT  = UPI_CPU0_CPU1_P1P0_DN<9>
  DH8  VSS1057  POWER  = GND
  DH10  PE2_RX_DN5  IN  = P5E_CPU0_PE2_RX_DN<5>
  DH12  VSS1039  POWER  = GND
  DH14  PE2_TX_DP6  OUT  = P5E_CPU0_PE2_TX_DP<6>
  DH16  VSS829  POWER  = GND
  DH18  DDR7_SB_DQS_DP8  BI  = M_H_CPU0_SB_DQS_DP<8>
  DH20  VSS830  POWER  = GND
  DH22  VSS1040  POWER  = GND
  DH24  DDR7_SB_DQS_DN6  BI  = M_H_CPU0_SB_DQS_DN<6>
  DH26  VSS832  POWER  = GND
  DH28  VSS1041  POWER  = GND
  DH30  DDR7_SB_DQS_DN5  BI  = M_H_CPU0_SB_DQS_DN<5>
  DH32  VSS1042  POWER  = GND
  DH34  VSS835  POWER  = GND
  DH36  DDR7_SB_DQS_DN4  BI  = M_H_CPU0_SB_DQS_DN<4>
  DH38  VSS1043  POWER  = GND
  DH40  VSS1045  POWER  = GND
  DH42  DDR7_CLK_DN0  OUT  = M_H_CPU0_CLK_DN<0>
  DH44  VSS839  POWER  = GND
  DH47  VSS1046  POWER  = GND
  DH49  DDR7_SA_CA1  OUT  = M_H_CPU0_SA_CA<1>
  DH51  VSS841  POWER  = GND
  DH53  VSS842  POWER  = GND
  DH55  DDR7_SA_DQS_DN9  BI  = M_H_CPU0_SA_DQS_DN<9>
  DH57  VSS1049  POWER  = GND
  DH59  VSS844  POWER  = GND
  DH61  DDR7_SA_DQS_DN8  BI  = M_H_CPU0_SA_DQS_DN<8>
  DH63  VSS845  POWER  = GND
  DH65  VSS1053  POWER  = GND
  DH67  DDR7_SA_DQS_DN7  BI  = M_H_CPU0_SA_DQS_DN<7>
  DH69  VSS847  POWER  = GND
  DH71  VSS1055  POWER  = GND
  DH73  DDR7_SA_DQS_DN6  BI  = M_H_CPU0_SA_DQS_DN<6>
  DH75  VSS849  POWER  = GND
  DH77  VSS1056  POWER  = GND
  DH79  UPI3_RX_DP10  IN  = GND
  DH81  UPI3_RX_DN11  IN  = GND
  DH83  UPI3_RX_DP12  IN  = GND
  DH85  VSS1058  POWER  = GND
  DH87  PE3_TX_DN8  OUT  = P5E_CPU0_PE3_TX_DN<8>
  DH89  VCCFA_EHV_FIVRA50  POWER  = PVCCFA_EHV_FIVRA_CPU0
  DH91  PE3_RX_DN9  IN  = P5E_CPU0_PE3_RX_DN<9>
  DJ1  UPI1_RX_DN9  IN  = UPI_CPU1_CPU0_P0P1_DN<9>
  DJ3  VCCINFAON31  POWER  = PVCCINFAON_CPU0
  DJ5  UPI1_TX_DP8  OUT  = UPI_CPU0_CPU1_P1P0_DP<8>
  DJ7  VCCINFAON32  POWER  = PVCCINFAON_CPU0
  DJ9  PE2_RX_DN6  IN  = P5E_CPU0_PE2_RX_DN<6>
  DJ11  VCCINFAON59  POWER  = PVCCINFAON_CPU0
  DJ13  PE2_TX_DN6  OUT  = P5E_CPU0_PE2_TX_DN<6>
  DJ15  VCCINFAON30  POWER  = PVCCINFAON_CPU0
  DJ17  DDR7_SB_DQ30  BI  = M_H_CPU0_SB_DQ<30>
  DJ19  VSS1061  POWER  = GND
  DJ21  DDR7_SB_DQS_DP2  BI  = M_H_CPU0_SB_DQS_DP<2>
  DJ23  VSS1062  POWER  = GND
  DJ25  VSS857  POWER  = GND
  DJ27  DDR6_SB_DQS_DN1  BI  = M_G_CPU0_SB_DQS_DN<1>
  DJ29  VSS1065  POWER  = GND
  DJ31  VSS1066  POWER  = GND
  DJ33  DDR6_SB_DQS_DN0  BI  = M_G_CPU0_SB_DQS_DN<0>
  DJ35  VSS861  POWER  = GND
  DJ37  VSS1067  POWER  = GND
  DJ39  DDR7_SB_CA6  OUT  = M_H_CPU0_SB_CA<6>
  DJ41  VSS1068  POWER  = GND
  DJ43  VSS1069  POWER  = GND
  DJ45  DDR6_CLK_DP1  OUT  = M_G_CPU0_CLK_DP<1>
  DJ48  VSS1070  POWER  = GND
  DJ50  VSS1071  POWER  = GND
  DJ52  DDR6_SA_CA0  OUT  = M_G_CPU0_SA_CA<0>
  DJ54  VSS867  POWER  = GND
  DJ56  VSS1072  POWER  = GND
  DJ58  DDR6_SA_DQS_DP4  BI  = M_G_CPU0_SA_DQS_DP<4>
  DJ60  VSS1073  POWER  = GND
  DJ62  VSS870  POWER  = GND
  DJ64  DDR6_SA_DQS_DP3  BI  = M_G_CPU0_SA_DQS_DP<3>
  DJ66  VSS1074  POWER  = GND
  DJ68  VSS872  POWER  = GND
  DJ70  DDR6_SA_DQS_DN1  BI  = M_G_CPU0_SA_DQS_DN<1>
  DJ72  VSS1075  POWER  = GND
  DJ74  VSS1076  POWER  = GND
  DJ76  DDR7_SA_DQS_DN0  BI  = M_H_CPU0_SA_DQS_DN<0>
  DJ78  UPI3_RX_DN9  IN  = GND
  DJ80  VSS1078  POWER  = GND
  DJ82  VSS1079  POWER  = GND
  DJ84  VSS1080  POWER  = GND
  DJ86  PE3_TX_DP8  OUT  = P5E_CPU0_PE3_TX_DP<8>
  DJ88  VSS1081  POWER  = GND
  DJ90  PE3_RX_DP9  IN  = P5E_CPU0_PE3_RX_DP<9>
  DK2  UPI1_RX_DP9  IN  = UPI_CPU1_CPU0_P0P1_DP<9>
  DK4  VSS1085  POWER  = GND
  DK6  UPI1_TX_DN8  OUT  = UPI_CPU0_CPU1_P1P0_DN<8>
  DK8  VSS1090  POWER  = GND
  DK10  PE2_RX_DP6  IN  = P5E_CPU0_PE2_RX_DP<6>
  DK12  VSS880  POWER  = GND
  DK14  PE2_TX_DN7  OUT  = P5E_CPU0_PE2_TX_DN<7>
  DK16  VSS1082  POWER  = GND
  DK18  VSS882  POWER  = GND
  DK20  DDR7_SB_DQ20  BI  = M_H_CPU0_SB_DQ<20>
  DK22  DDR7_SB_DQ17  BI  = M_H_CPU0_SB_DQ<17>
  DK24  VSS883  POWER  = GND
  DK26  DDR6_SB_DQ12  BI  = M_G_CPU0_SB_DQ<12>
  DK28  DDR6_SB_DQ9  BI  = M_G_CPU0_SB_DQ<9>
  DK30  VSS1083  POWER  = GND
  DK32  DDR6_SB_DQ4  BI  = M_G_CPU0_SB_DQ<4>
  DK34  DDR6_SB_DQ1  BI  = M_G_CPU0_SB_DQ<1>
  DK36  VSS1084  POWER  = GND
  DK38  DDR7_SB_CS_N2  OUT  = M_H_CPU0_SB_CS_N<2>
  DK40  DDR7_SB_CA4  OUT  = M_H_CPU0_SB_CA<4>
  DK42  VSS887  POWER  = GND
  DK44  DDR6_SA_CA6  OUT  = M_G_CPU0_SA_CA<6>
  DK47  DDR5_B_RSP1  IN  = M_F_CPU0_SB_RSP<1>
  DK49  VSS1086  POWER  = GND
  DK51  DDR6_SA_CA2  OUT  = M_G_CPU0_SA_CA<2>
  DK53  DDR6_SA_CS_N3  OUT  = M_G_CPU0_SA_CS_N<3>
  DK55  VSS890  POWER  = GND
  DK57  DDR6_SA_ECC4  BI  = M_G_CPU0_SA_CB<4>
  DK59  DDR6_SA_ECC1  BI  = M_G_CPU0_SA_CB<1>
  DK61  VSS893  POWER  = GND
  DK63  DDR6_SA_DQ28  BI  = M_G_CPU0_SA_DQ<28>
  DK65  DDR6_SA_DQ25  BI  = M_G_CPU0_SA_DQ<25>
  DK67  VSS894  POWER  = GND
  DK69  DDR6_SA_DQ12  BI  = M_G_CPU0_SA_DQ<12>
  DK71  DDR6_SA_DQ9  BI  = M_G_CPU0_SA_DQ<9>
  DK73  VSS1087  POWER  = GND
  DK75  DDR7_SA_DQ4  BI  = M_H_CPU0_SA_DQ<4>
  DK77  VSS1088  POWER  = GND
  DK79  VSS1089  POWER  = GND
  DK81  VSS1091  POWER  = GND
  DK83  VSS1092  POWER  = GND
  DK85  PE3_TX_DN7  OUT  = P5E_CPU0_PE3_TX_DN<7>
  DK87  VSS1093  POWER  = GND
  DK89  PE3_RX_DP8  IN  = P5E_CPU0_PE3_RX_DP<8>
  DK91  VSS1094  POWER  = GND
  DL1  VSS903  POWER  = GND
  DL3  UPI1_RX_DN8  IN  = UPI_CPU1_CPU0_P0P1_DN<8>
  DL5  VSS908  POWER  = GND
  DL7  UPI1_TX_DN7  OUT  = UPI_CPU0_CPU1_P1P0_DN<7>
  DL9  VSS1099  POWER  = GND
  DL11  PE2_RX_DP7  IN  = P5E_CPU0_PE2_RX_DP<7>
  DL13  VSS904  POWER  = GND
  DL15  PE2_TX_DP7  OUT  = P5E_CPU0_PE2_TX_DP<7>
  DL17  VSS905  POWER  = GND
  DL19  DDR7_SB_DQ21  BI  = M_H_CPU0_SB_DQ<21>
  DL21  DDR7_SB_DQS_DN2  BI  = M_H_CPU0_SB_DQS_DN<2>
  DL23  DDR7_SB_DQ16  BI  = M_H_CPU0_SB_DQ<16>
  DL25  DDR6_SB_DQ13  BI  = M_G_CPU0_SB_DQ<13>
  DL27  DDR6_SB_DQS_DP1  BI  = M_G_CPU0_SB_DQS_DP<1>
  DL29  DDR6_SB_DQ10  BI  = M_G_CPU0_SB_DQ<10>
  DL31  DDR6_SB_DQ5  BI  = M_G_CPU0_SB_DQ<5>
  DL33  DDR6_SB_DQS_DP0  BI  = M_G_CPU0_SB_DQS_DP<0>
  DL35  DDR6_SB_DQ0  BI  = M_G_CPU0_SB_DQ<0>
  DL37  DDR7_SB_CS_N0  OUT  = M_H_CPU0_SB_CS_N<0>
  DL39  VSS1095  POWER  = GND
  DL41  DDR7_SB_CA2  OUT  = M_H_CPU0_SB_CA<2>
  DL43  DDR6_SA_PAR  OUT  = M_G_CPU0_SA_PAR
  DL45  DDR6_CLK_DN1  OUT  = M_G_CPU0_CLK_DN<1>
  DL48  DDR5_B_RSP0  IN  = M_F_CPU0_SB_RSP<0>
  DL50  DDR6_SA_CA4  OUT  = M_G_CPU0_SA_CA<4>
  DL52  VSS909  POWER  = GND
  DL54  DDR6_SA_CS_N2  OUT  = M_G_CPU0_SA_CS_N<2>
  DL56  DDR6_SA_ECC5  BI  = M_G_CPU0_SA_CB<5>
  DL58  DDR6_SA_DQS_DN4  BI  = M_G_CPU0_SA_DQS_DN<4>
  DL60  DDR6_SA_ECC0  BI  = M_G_CPU0_SA_CB<0>
  DL62  DDR6_SA_DQ29  BI  = M_G_CPU0_SA_DQ<29>
  DL64  DDR6_SA_DQS_DN3  BI  = M_G_CPU0_SA_DQS_DN<3>
  DL66  DDR6_SA_DQ24  BI  = M_G_CPU0_SA_DQ<24>
  DL68  DDR6_SA_DQ13  BI  = M_G_CPU0_SA_DQ<13>
  DL70  DDR6_SA_DQS_DP1  BI  = M_G_CPU0_SA_DQS_DP<1>
  DL72  DDR6_SA_DQ8  BI  = M_G_CPU0_SA_DQ<8>
  DL74  DDR7_SA_DQ5  BI  = M_H_CPU0_SA_DQ<5>
  DL76  DDR7_SA_DQS_DP0  BI  = M_H_CPU0_SA_DQS_DP<0>
  DL78  UPI3_RX_DP9  IN  = GND
  DL80  UPI3_TX_DN11  OUT  = NC
  DL82  UPI3_TX_DP10  OUT  = NC
  DL84  VSS1096  POWER  = GND
  DL86  PE3_TX_DP7  OUT  = P5E_CPU0_PE3_TX_DP<7>
  DL88  VSS1098  POWER  = GND
  DL90  PE3_RX_DN8  IN  = P5E_CPU0_PE3_RX_DN<8>
  DM2  UPI1_RX_DP8  IN  = UPI_CPU1_CPU0_P0P1_DP<8>
  DM4  VSS1117  POWER  = GND
  DM6  UPI1_TX_DP7  OUT  = UPI_CPU0_CPU1_P1P0_DP<7>
  DM8  VSS1140  POWER  = GND
  DM10  PE2_RX_DN7  IN  = P5E_CPU0_PE2_RX_DN<7>
  DM12  VSS1100  POWER  = GND
  DM14  PE2_TX_DP8  OUT  = P5E_CPU0_PE2_TX_DP<8>
  DM16  VSS1101  POWER  = GND
  DM18  VSS1102  POWER  = GND
  DM20  VSS1103  POWER  = GND
  DM22  VSS1104  POWER  = GND
  DM24  VSS1105  POWER  = GND
  DM26  VSS1106  POWER  = GND
  DM28  VSS1107  POWER  = GND
  DM30  VSS1108  POWER  = GND
  DM32  VSS1109  POWER  = GND
  DM34  VSS1110  POWER  = GND
  DM36  VSS1113  POWER  = GND
  DM38  VSS1114  POWER  = GND
  DM40  VSS1118  POWER  = GND
  DM42  VSS1119  POWER  = GND
  DM44  VSS1120  POWER  = GND
  DM47  VSS1121  POWER  = GND
  DM49  VSS1122  POWER  = GND
  DM51  VSS934  POWER  = GND
  DM53  VSS1123  POWER  = GND
  DM55  VSS1124  POWER  = GND
  DM57  VSS1127  POWER  = GND
  DM59  VSS1128  POWER  = GND
  DM61  VSS1130  POWER  = GND
  DM63  VSS1132  POWER  = GND
  DM65  VSS1133  POWER  = GND
  DM67  VSS1134  POWER  = GND
  DM69  VSS1135  POWER  = GND
  DM71  VSS1136  POWER  = GND
  DM73  VSS945  POWER  = GND
  DM75  VSS1137  POWER  = GND
  DM77  VSS1138  POWER  = GND
  DM79  VSS1139  POWER  = GND
  DM81  UPI3_TX_DN10  OUT  = NC
  DM83  VCCFA_EHV_FIVRA51  POWER  = PVCCFA_EHV_FIVRA_CPU0
  DM85  VCCFA_EHV_FIVRA52  POWER  = PVCCFA_EHV_FIVRA_CPU0
  DM87  PE3_TX_DN6  OUT  = P5E_CPU0_PE3_TX_DN<6>
  DM89  VCCFA_EHV_FIVRA53  POWER  = PVCCFA_EHV_FIVRA_CPU0
  DM91  PE3_RX_DP7  IN  = P5E_CPU0_PE3_RX_DP<7>
  DN1  UPI1_RX_DN7  IN  = UPI_CPU1_CPU0_P0P1_DN<7>
  DN3  VCCFA_EHV_FIVRA56  POWER  = PVCCFA_EHV_FIVRA_CPU0
  DN5  UPI1_TX_DP6  OUT  = UPI_CPU0_CPU1_P1P0_DP<6>
  DN7  VCCFA_EHV_FIVRA57  POWER  = PVCCFA_EHV_FIVRA_CPU0
